(kicad_pcb
	(version 20260206)
	(generator "pcbnew")
	(generator_version "10.0")
	(general
		(thickness 1.6)
		(legacy_teardrops no)
	)
	(paper "A4")
	(title_block
		(title "riser — 13919-sa.brd")
		(comment 1 "Honey Badger (Wiwynn) / footprint 2 of 2 (CN1), pads 1-76 of 166")
	)
	(layers
		(0 "F.Cu" signal "TOP")
		(4 "In1.Cu" signal "L2VCC")
		(6 "In2.Cu" signal "L3GND")
		(2 "B.Cu" signal "BOTTOM")
		(9 "F.Adhes" user "F.Adhesive")
		(11 "B.Adhes" user "B.Adhesive")
		(13 "F.Paste" user "Package Geometry/Pastemask Top")
		(15 "B.Paste" user "Package Geometry/Pastemask Bottom")
		(5 "F.SilkS" user "Ref Des/Silkscreen Top")
		(7 "B.SilkS" user "Ref Des/Silkscreen Bottom")
		(1 "F.Mask" user "Board Geometry/Soldermask Top")
		(3 "B.Mask" user "Board Geometry/Soldermask Bottom")
		(17 "Dwgs.User" user "User.Drawings")
		(19 "Cmts.User" user "User.Comments")
		(21 "Eco1.User" user "User.Eco1")
		(23 "Eco2.User" user "User.Eco2")
		(25 "Edge.Cuts" user "Board Geometry/Outline")
		(27 "Margin" user)
		(31 "F.CrtYd" user "Package Geometry/Place Bound Top")
		(29 "B.CrtYd" user "Package Geometry/Place Bound Bottom")
		(35 "F.Fab" user "Ref Des/Assembly Top")
		(33 "B.Fab" user "Ref Des/Assembly Bottom")
	)
	(footprint ""
		(layer "F.Cu")
		(at 77.350112 -19.899884 180)
		(property "Reference" "CN1"
			(at 0 0 180)
			(layer "F.SilkS")
			(hide yes)
			(effects
				(font
					(size 1.27 1.27)
				)
			)
		)
		(property "Value" "PCISLT164-44-GP"
			(at -23.3172 -6.8961 180)
			(unlocked yes)
			(layer "F.Fab")
			(hide yes)
			(effects
				(font
					(size 1.016 1.016)
					(thickness 0.1524)
				)
			)
		)
		(property "Device Type" "AAA-PCI-066-K06"
			(at -23.3172 -8.4201 180)
			(unlocked yes)
			(layer "F.Fab")
			(hide yes)
			(effects
				(font
					(size 1.016 1.016)
					(thickness 0.1524)
				)
			)
		)
		(duplicate_pad_numbers_are_jumpers no)
		(pad "" np_thru_hole circle
			(at 0 0 180)
			(size 0.254 0.254)
			(drill 2.3622)
			(layers "*.Cu" "*.Mask")
			(clearance 1.4097)
			(thermal_gap 1.4097)
		)
		(pad "" np_thru_hole circle
			(at 73.14946 0 180)
			(size 0.254 0.254)
			(drill 2.3622)
			(layers "*.Cu" "*.Mask")
			(clearance 1.4097)
			(thermal_gap 1.4097)
		)
		(pad "A1" thru_hole circle
			(at -11.64971 -1.24968 180)
			(size 1.0922 1.0922)
			(drill 0.7366)
			(layers "*.Cu" "*.Mask")
			(remove_unused_layers no)
			(net "BOARD_PRSNT#")
			(clearance 0.1778)
			(thermal_gap 0.1778)
		)
		(pad "A2" thru_hole circle
			(at -10.65022 -3.24993 180)
			(size 1.0922 1.0922)
			(drill 0.7366)
			(layers "*.Cu" "*.Mask")
			(remove_unused_layers no)
			(net "P12V")
			(clearance 0.1778)
			(thermal_gap 0.1778)
		)
		(pad "A3" thru_hole circle
			(at -9.64946 -1.24968 180)
			(size 1.0922 1.0922)
			(drill 0.7366)
			(layers "*.Cu" "*.Mask")
			(remove_unused_layers no)
			(net "P12V")
			(clearance 0.1778)
			(thermal_gap 0.1778)
		)
		(pad "A4" thru_hole circle
			(at -8.64997 -3.24993 180)
			(size 1.0922 1.0922)
			(drill 0.7366)
			(layers "*.Cu" "*.Mask")
			(remove_unused_layers no)
			(net "GND")
			(clearance 0.1778)
			(thermal_gap 0.1778)
		)
		(pad "A5" thru_hole circle
			(at -7.65048 -1.24968 180)
			(size 1.0922 1.0922)
			(drill 0.7366)
			(layers "*.Cu" "*.Mask")
			(remove_unused_layers no)
			(net "SLOT_ID0")
			(clearance 0.1778)
			(thermal_gap 0.1778)
		)
		(pad "A6" thru_hole circle
			(at -6.64972 -3.24993 180)
			(size 1.0922 1.0922)
			(drill 0.7366)
			(layers "*.Cu" "*.Mask")
			(remove_unused_layers no)
			(net "SLOT_ID1")
			(clearance 0.1778)
			(thermal_gap 0.1778)
		)
		(pad "A7" thru_hole circle
			(at -5.65023 -1.24968 180)
			(size 1.0922 1.0922)
			(drill 0.7366)
			(layers "*.Cu" "*.Mask")
			(remove_unused_layers no)
			(net "CPU_TXD")
			(clearance 0.1778)
			(thermal_gap 0.1778)
		)
		(pad "A8" thru_hole circle
			(at -4.64947 -3.24993 180)
			(size 1.0922 1.0922)
			(drill 0.7366)
			(layers "*.Cu" "*.Mask")
			(remove_unused_layers no)
			(net "CPU_RXD")
			(clearance 0.1778)
			(thermal_gap 0.1778)
		)
		(pad "A9" thru_hole circle
			(at -3.64998 -1.24968 180)
			(size 1.0922 1.0922)
			(drill 0.7366)
			(layers "*.Cu" "*.Mask")
			(remove_unused_layers no)
			(net "SLOT_ID2")
			(clearance 0.1778)
			(thermal_gap 0.1778)
		)
		(pad "A10" thru_hole circle
			(at -2.65049 -3.24993 180)
			(size 1.0922 1.0922)
			(drill 0.7366)
			(layers "*.Cu" "*.Mask")
			(remove_unused_layers no)
			(net "SLOT_ID3")
			(clearance 0.1778)
			(thermal_gap 0.1778)
		)
		(pad "A11" thru_hole circle
			(at -1.64973 -1.24968 180)
			(size 1.0922 1.0922)
			(drill 0.7366)
			(layers "*.Cu" "*.Mask")
			(remove_unused_layers no)
			(net "PCIE_RESET#")
			(clearance 0.1778)
			(thermal_gap 0.1778)
		)
		(pad "A12" thru_hole circle
			(at 1.35001 -3.24993 180)
			(size 1.0922 1.0922)
			(drill 0.7366)
			(layers "*.Cu" "*.Mask")
			(remove_unused_layers no)
			(net "GND")
			(clearance 0.1778)
			(thermal_gap 0.1778)
		)
		(pad "A13" thru_hole circle
			(at 2.3495 -1.24968 180)
			(size 1.0922 1.0922)
			(drill 0.7366)
			(layers "*.Cu" "*.Mask")
			(remove_unused_layers no)
			(net "CLK_100M_PCIE_SAS_C_P")
			(clearance 0.1778)
			(thermal_gap 0.1778)
		)
		(pad "A14" thru_hole circle
			(at 3.35026 -3.24993 180)
			(size 1.0922 1.0922)
			(drill 0.7366)
			(layers "*.Cu" "*.Mask")
			(remove_unused_layers no)
			(net "CLK_100M_PCIE_SAS_C_N")
			(clearance 0.1778)
			(thermal_gap 0.1778)
		)
		(pad "A15" thru_hole circle
			(at 4.34975 -1.24968 180)
			(size 1.0922 1.0922)
			(drill 0.7366)
			(layers "*.Cu" "*.Mask")
			(remove_unused_layers no)
			(net "GND")
			(clearance 0.1778)
			(thermal_gap 0.1778)
		)
		(pad "A16" thru_hole circle
			(at 5.35051 -3.24993 180)
			(size 1.0922 1.0922)
			(drill 0.7366)
			(layers "*.Cu" "*.Mask")
			(remove_unused_layers no)
			(net "GND")
			(clearance 0.1778)
			(thermal_gap 0.1778)
		)
		(pad "A17" thru_hole circle
			(at 6.35 -1.24968 180)
			(size 1.0922 1.0922)
			(drill 0.7366)
			(layers "*.Cu" "*.Mask")
			(remove_unused_layers no)
			(net "P2E_CPU_SAS_RX_DP0")
			(clearance 0.1778)
			(thermal_gap 0.1778)
		)
		(pad "A18" thru_hole circle
			(at 7.34949 -3.24993 180)
			(size 1.0922 1.0922)
			(drill 0.7366)
			(layers "*.Cu" "*.Mask")
			(remove_unused_layers no)
			(net "P2E_CPU_SAS_RX_DN0")
			(clearance 0.1778)
			(thermal_gap 0.1778)
		)
		(pad "A19" thru_hole circle
			(at 8.35025 -1.24968 180)
			(size 1.0922 1.0922)
			(drill 0.7366)
			(layers "*.Cu" "*.Mask")
			(remove_unused_layers no)
			(net "GND")
			(clearance 0.1778)
			(thermal_gap 0.1778)
		)
		(pad "A20" thru_hole circle
			(at 9.34974 -3.24993 180)
			(size 1.0922 1.0922)
			(drill 0.7366)
			(layers "*.Cu" "*.Mask")
			(remove_unused_layers no)
			(net "GND")
			(clearance 0.1778)
			(thermal_gap 0.1778)
		)
		(pad "A21" thru_hole circle
			(at 10.3505 -1.24968 180)
			(size 1.0922 1.0922)
			(drill 0.7366)
			(layers "*.Cu" "*.Mask")
			(remove_unused_layers no)
			(net "P2E_CPU_SAS_RX_DP1")
			(clearance 0.1778)
			(thermal_gap 0.1778)
		)
		(pad "A22" thru_hole circle
			(at 11.34999 -3.24993 180)
			(size 1.0922 1.0922)
			(drill 0.7366)
			(layers "*.Cu" "*.Mask")
			(remove_unused_layers no)
			(net "P2E_CPU_SAS_RX_DN1")
			(clearance 0.1778)
			(thermal_gap 0.1778)
		)
		(pad "A23" thru_hole circle
			(at 12.34948 -1.24968 180)
			(size 1.0922 1.0922)
			(drill 0.7366)
			(layers "*.Cu" "*.Mask")
			(remove_unused_layers no)
			(net "GND")
			(clearance 0.1778)
			(thermal_gap 0.1778)
		)
		(pad "A24" thru_hole circle
			(at 13.35024 -3.24993 180)
			(size 1.0922 1.0922)
			(drill 0.7366)
			(layers "*.Cu" "*.Mask")
			(remove_unused_layers no)
			(net "GND")
			(clearance 0.1778)
			(thermal_gap 0.1778)
		)
		(pad "A25" thru_hole circle
			(at 14.34973 -1.24968 180)
			(size 1.0922 1.0922)
			(drill 0.7366)
			(layers "*.Cu" "*.Mask")
			(remove_unused_layers no)
			(net "P2E_CPU_SAS_RX_DP2")
			(clearance 0.1778)
			(thermal_gap 0.1778)
		)
		(pad "A26" thru_hole circle
			(at 15.35049 -3.24993 180)
			(size 1.0922 1.0922)
			(drill 0.7366)
			(layers "*.Cu" "*.Mask")
			(remove_unused_layers no)
			(net "P2E_CPU_SAS_RX_DN2")
			(clearance 0.1778)
			(thermal_gap 0.1778)
		)
		(pad "A27" thru_hole circle
			(at 16.34998 -1.24968 180)
			(size 1.0922 1.0922)
			(drill 0.7366)
			(layers "*.Cu" "*.Mask")
			(remove_unused_layers no)
			(net "GND")
			(clearance 0.1778)
			(thermal_gap 0.1778)
		)
		(pad "A28" thru_hole circle
			(at 17.34947 -3.24993 180)
			(size 1.0922 1.0922)
			(drill 0.7366)
			(layers "*.Cu" "*.Mask")
			(remove_unused_layers no)
			(net "GND")
			(clearance 0.1778)
			(thermal_gap 0.1778)
		)
		(pad "A29" thru_hole circle
			(at 18.35023 -1.24968 180)
			(size 1.0922 1.0922)
			(drill 0.7366)
			(layers "*.Cu" "*.Mask")
			(remove_unused_layers no)
			(net "P2E_CPU_SAS_RX_DP3")
			(clearance 0.1778)
			(thermal_gap 0.1778)
		)
		(pad "A30" thru_hole circle
			(at 19.34972 -3.24993 180)
			(size 1.0922 1.0922)
			(drill 0.7366)
			(layers "*.Cu" "*.Mask")
			(remove_unused_layers no)
			(net "P2E_CPU_SAS_RX_DN3")
			(clearance 0.1778)
			(thermal_gap 0.1778)
		)
		(pad "A31" thru_hole circle
			(at 20.35048 -1.24968 180)
			(size 1.0922 1.0922)
			(drill 0.7366)
			(layers "*.Cu" "*.Mask")
			(remove_unused_layers no)
			(net "GND")
			(clearance 0.1778)
			(thermal_gap 0.1778)
		)
		(pad "A32" thru_hole circle
			(at 21.34997 -3.24993 180)
			(size 1.0922 1.0922)
			(drill 0.7366)
			(layers "*.Cu" "*.Mask")
			(remove_unused_layers no)
			(net "GND")
			(clearance 0.1778)
			(thermal_gap 0.1778)
		)
		(pad "A33" thru_hole circle
			(at 22.34946 -1.24968 180)
			(size 1.0922 1.0922)
			(drill 0.7366)
			(layers "*.Cu" "*.Mask")
			(remove_unused_layers no)
			(net "SATA2_RX_C_DP0")
			(clearance 0.1778)
			(thermal_gap 0.1778)
		)
		(pad "A34" thru_hole circle
			(at 23.35022 -3.24993 180)
			(size 1.0922 1.0922)
			(drill 0.7366)
			(layers "*.Cu" "*.Mask")
			(remove_unused_layers no)
			(net "SATA2_RX_C_DN0")
			(clearance 0.1778)
			(thermal_gap 0.1778)
		)
		(pad "A35" thru_hole circle
			(at 24.34971 -1.24968 180)
			(size 1.0922 1.0922)
			(drill 0.7366)
			(layers "*.Cu" "*.Mask")
			(remove_unused_layers no)
			(net "GND")
			(clearance 0.1778)
			(thermal_gap 0.1778)
		)
		(pad "A36" thru_hole circle
			(at 25.35047 -3.24993 180)
			(size 1.0922 1.0922)
			(drill 0.7366)
			(layers "*.Cu" "*.Mask")
			(remove_unused_layers no)
			(net "GND")
			(clearance 0.1778)
			(thermal_gap 0.1778)
		)
		(pad "A37" thru_hole circle
			(at 26.34996 -1.24968 180)
			(size 1.0922 1.0922)
			(drill 0.7366)
			(layers "*.Cu" "*.Mask")
			(remove_unused_layers no)
			(net "PCIE_RSVD_A37")
			(clearance 0.1778)
			(thermal_gap 0.1778)
		)
		(pad "A38" thru_hole circle
			(at 27.34945 -3.24993 180)
			(size 1.0922 1.0922)
			(drill 0.7366)
			(layers "*.Cu" "*.Mask")
			(remove_unused_layers no)
			(net "PCIE_RSVD_A38")
			(clearance 0.1778)
			(thermal_gap 0.1778)
		)
		(pad "A39" thru_hole circle
			(at 28.35021 -1.24968 180)
			(size 1.0922 1.0922)
			(drill 0.7366)
			(layers "*.Cu" "*.Mask")
			(remove_unused_layers no)
			(net "GND")
			(clearance 0.1778)
			(thermal_gap 0.1778)
		)
		(pad "A40" thru_hole circle
			(at 29.3497 -3.24993 180)
			(size 1.0922 1.0922)
			(drill 0.7366)
			(layers "*.Cu" "*.Mask")
			(remove_unused_layers no)
			(net "GND")
			(clearance 0.1778)
			(thermal_gap 0.1778)
		)
		(pad "A41" thru_hole circle
			(at 30.35046 -1.24968 180)
			(size 1.0922 1.0922)
			(drill 0.7366)
			(layers "*.Cu" "*.Mask")
			(remove_unused_layers no)
			(net "PCIE_RSVD_A41")
			(clearance 0.1778)
			(thermal_gap 0.1778)
		)
		(pad "A42" thru_hole circle
			(at 31.34995 -3.24993 180)
			(size 1.0922 1.0922)
			(drill 0.7366)
			(layers "*.Cu" "*.Mask")
			(remove_unused_layers no)
			(net "GBE_SMBALRT_R#")
			(clearance 0.1778)
			(thermal_gap 0.1778)
		)
		(pad "A43" thru_hole circle
			(at 32.34944 -1.24968 180)
			(size 1.0922 1.0922)
			(drill 0.7366)
			(layers "*.Cu" "*.Mask")
			(remove_unused_layers no)
			(net "GND")
			(clearance 0.1778)
			(thermal_gap 0.1778)
		)
		(pad "A44" thru_hole circle
			(at 33.3502 -3.24993 180)
			(size 1.0922 1.0922)
			(drill 0.7366)
			(layers "*.Cu" "*.Mask")
			(remove_unused_layers no)
			(net "GND")
			(clearance 0.1778)
			(thermal_gap 0.1778)
		)
		(pad "A45" thru_hole circle
			(at 34.34969 -1.24968 180)
			(size 1.0922 1.0922)
			(drill 0.7366)
			(layers "*.Cu" "*.Mask")
			(remove_unused_layers no)
			(net "CPU_GBE_RX_C_DP0")
			(clearance 0.1778)
			(thermal_gap 0.1778)
		)
		(pad "A46" thru_hole circle
			(at 35.35045 -3.24993 180)
			(size 1.0922 1.0922)
			(drill 0.7366)
			(layers "*.Cu" "*.Mask")
			(remove_unused_layers no)
			(net "CPU_GBE_RX_C_DN0")
			(clearance 0.1778)
			(thermal_gap 0.1778)
		)
		(pad "A47" thru_hole circle
			(at 36.34994 -1.24968 180)
			(size 1.0922 1.0922)
			(drill 0.7366)
			(layers "*.Cu" "*.Mask")
			(remove_unused_layers no)
			(net "GND")
			(clearance 0.1778)
			(thermal_gap 0.1778)
		)
		(pad "A48" thru_hole circle
			(at 37.34943 -3.24993 180)
			(size 1.0922 1.0922)
			(drill 0.7366)
			(layers "*.Cu" "*.Mask")
			(remove_unused_layers no)
			(net "GND")
			(clearance 0.1778)
			(thermal_gap 0.1778)
		)
		(pad "A49" thru_hole circle
			(at 38.35019 -1.24968 180)
			(size 1.0922 1.0922)
			(drill 0.7366)
			(layers "*.Cu" "*.Mask")
			(remove_unused_layers no)
			(net "P2E_CPU_SAS_RX_DP4")
			(clearance 0.1778)
			(thermal_gap 0.1778)
		)
		(pad "A50" thru_hole circle
			(at 39.34968 -3.24993 180)
			(size 1.0922 1.0922)
			(drill 0.7366)
			(layers "*.Cu" "*.Mask")
			(remove_unused_layers no)
			(net "P2E_CPU_SAS_RX_DN4")
			(clearance 0.1778)
			(thermal_gap 0.1778)
		)
		(pad "A51" thru_hole circle
			(at 40.35044 -1.24968 180)
			(size 1.0922 1.0922)
			(drill 0.7366)
			(layers "*.Cu" "*.Mask")
			(remove_unused_layers no)
			(net "GND")
			(clearance 0.1778)
			(thermal_gap 0.1778)
		)
		(pad "A52" thru_hole circle
			(at 41.34993 -3.24993 180)
			(size 1.0922 1.0922)
			(drill 0.7366)
			(layers "*.Cu" "*.Mask")
			(remove_unused_layers no)
			(net "GND")
			(clearance 0.1778)
			(thermal_gap 0.1778)
		)
		(pad "A53" thru_hole circle
			(at 42.34942 -1.24968 180)
			(size 1.0922 1.0922)
			(drill 0.7366)
			(layers "*.Cu" "*.Mask")
			(remove_unused_layers no)
			(net "P2E_CPU_SAS_RX_DP5")
			(clearance 0.1778)
			(thermal_gap 0.1778)
		)
		(pad "A54" thru_hole circle
			(at 43.35018 -3.24993 180)
			(size 1.0922 1.0922)
			(drill 0.7366)
			(layers "*.Cu" "*.Mask")
			(remove_unused_layers no)
			(net "P2E_CPU_SAS_RX_DN5")
			(clearance 0.1778)
			(thermal_gap 0.1778)
		)
		(pad "A55" thru_hole circle
			(at 44.34967 -1.24968 180)
			(size 1.0922 1.0922)
			(drill 0.7366)
			(layers "*.Cu" "*.Mask")
			(remove_unused_layers no)
			(net "GND")
			(clearance 0.1778)
			(thermal_gap 0.1778)
		)
		(pad "A56" thru_hole circle
			(at 45.35043 -3.24993 180)
			(size 1.0922 1.0922)
			(drill 0.7366)
			(layers "*.Cu" "*.Mask")
			(remove_unused_layers no)
			(net "GND")
			(clearance 0.1778)
			(thermal_gap 0.1778)
		)
		(pad "A57" thru_hole circle
			(at 46.34992 -1.24968 180)
			(size 1.0922 1.0922)
			(drill 0.7366)
			(layers "*.Cu" "*.Mask")
			(remove_unused_layers no)
			(net "P2E_CPU_SAS_RX_DP6")
			(clearance 0.1778)
			(thermal_gap 0.1778)
		)
		(pad "A58" thru_hole circle
			(at 47.34941 -3.24993 180)
			(size 1.0922 1.0922)
			(drill 0.7366)
			(layers "*.Cu" "*.Mask")
			(remove_unused_layers no)
			(net "P2E_CPU_SAS_RX_DN6")
			(clearance 0.1778)
			(thermal_gap 0.1778)
		)
		(pad "A59" thru_hole circle
			(at 48.35017 -1.24968 180)
			(size 1.0922 1.0922)
			(drill 0.7366)
			(layers "*.Cu" "*.Mask")
			(remove_unused_layers no)
			(net "GND")
			(clearance 0.1778)
			(thermal_gap 0.1778)
		)
		(pad "A60" thru_hole circle
			(at 49.34966 -3.24993 180)
			(size 1.0922 1.0922)
			(drill 0.7366)
			(layers "*.Cu" "*.Mask")
			(remove_unused_layers no)
			(net "GND")
			(clearance 0.1778)
			(thermal_gap 0.1778)
		)
		(pad "A61" thru_hole circle
			(at 50.35042 -1.24968 180)
			(size 1.0922 1.0922)
			(drill 0.7366)
			(layers "*.Cu" "*.Mask")
			(remove_unused_layers no)
			(net "P2E_CPU_SAS_RX_DP7")
			(clearance 0.1778)
			(thermal_gap 0.1778)
		)
		(pad "A62" thru_hole circle
			(at 51.34991 -3.24993 180)
			(size 1.0922 1.0922)
			(drill 0.7366)
			(layers "*.Cu" "*.Mask")
			(remove_unused_layers no)
			(net "P2E_CPU_SAS_RX_DN7")
			(clearance 0.1778)
			(thermal_gap 0.1778)
		)
		(pad "A63" thru_hole circle
			(at 52.3494 -1.24968 180)
			(size 1.0922 1.0922)
			(drill 0.7366)
			(layers "*.Cu" "*.Mask")
			(remove_unused_layers no)
			(net "GND")
			(clearance 0.1778)
			(thermal_gap 0.1778)
		)
		(pad "A64" thru_hole circle
			(at 53.35016 -3.24993 180)
			(size 1.0922 1.0922)
			(drill 0.7366)
			(layers "*.Cu" "*.Mask")
			(remove_unused_layers no)
			(net "GND")
			(clearance 0.1778)
			(thermal_gap 0.1778)
		)
		(pad "A65" thru_hole circle
			(at 54.34965 -1.24968 180)
			(size 1.0922 1.0922)
			(drill 0.7366)
			(layers "*.Cu" "*.Mask")
			(remove_unused_layers no)
			(net "P2E_CPU_ETH10G_RX_DP8")
			(clearance 0.1778)
			(thermal_gap 0.1778)
		)
		(pad "A66" thru_hole circle
			(at 55.35041 -3.24993 180)
			(size 1.0922 1.0922)
			(drill 0.7366)
			(layers "*.Cu" "*.Mask")
			(remove_unused_layers no)
			(net "P2E_CPU_ETH10G_RX_DN8")
			(clearance 0.1778)
			(thermal_gap 0.1778)
		)
		(pad "A67" thru_hole circle
			(at 56.3499 -1.24968 180)
			(size 1.0922 1.0922)
			(drill 0.7366)
			(layers "*.Cu" "*.Mask")
			(remove_unused_layers no)
			(net "GND")
			(clearance 0.1778)
			(thermal_gap 0.1778)
		)
		(pad "A68" thru_hole circle
			(at 57.34939 -3.24993 180)
			(size 1.0922 1.0922)
			(drill 0.7366)
			(layers "*.Cu" "*.Mask")
			(remove_unused_layers no)
			(net "GND")
			(clearance 0.1778)
			(thermal_gap 0.1778)
		)
		(pad "A69" thru_hole circle
			(at 58.35015 -1.24968 180)
			(size 1.0922 1.0922)
			(drill 0.7366)
			(layers "*.Cu" "*.Mask")
			(remove_unused_layers no)
			(net "P2E_CPU_ETH10G_RX_DP9")
			(clearance 0.1778)
			(thermal_gap 0.1778)
		)
		(pad "A70" thru_hole circle
			(at 59.34964 -3.24993 180)
			(size 1.0922 1.0922)
			(drill 0.7366)
			(layers "*.Cu" "*.Mask")
			(remove_unused_layers no)
			(net "P2E_CPU_ETH10G_RX_DN9")
			(clearance 0.1778)
			(thermal_gap 0.1778)
		)
		(pad "A71" thru_hole circle
			(at 60.3504 -1.24968 180)
			(size 1.0922 1.0922)
			(drill 0.7366)
			(layers "*.Cu" "*.Mask")
			(remove_unused_layers no)
			(net "GND")
			(clearance 0.1778)
			(thermal_gap 0.1778)
		)
		(pad "A72" thru_hole circle
			(at 61.34989 -3.24993 180)
			(size 1.0922 1.0922)
			(drill 0.7366)
			(layers "*.Cu" "*.Mask")
			(remove_unused_layers no)
			(net "GND")
			(clearance 0.1778)
			(thermal_gap 0.1778)
		)
		(pad "A73" thru_hole circle
			(at 62.34938 -1.24968 180)
			(size 1.0922 1.0922)
			(drill 0.7366)
			(layers "*.Cu" "*.Mask")
			(remove_unused_layers no)
			(net "P2E_CPU_ETH10G_RX_DP10")
			(clearance 0.1778)
			(thermal_gap 0.1778)
		)
		(pad "A74" thru_hole circle
			(at 63.35014 -3.24993 180)
			(size 1.0922 1.0922)
			(drill 0.7366)
			(layers "*.Cu" "*.Mask")
			(remove_unused_layers no)
			(net "P2E_CPU_ETH10G_RX_DN10")
			(clearance 0.1778)
			(thermal_gap 0.1778)
		)
	)
)
